(kicad_pcb
	(version 20241229)
	(generator "pcbnew")
	(generator_version "9.0")
	(general
		(thickness 1.63)
		(legacy_teardrops no)
	)
	(paper "A4")
	(title_block
		(title "CM4 Baseboard")
		(date "2026-01-05")
		(rev "1.1.1")
		(company "Antmicro Ltd")
		(comment 1 "www.antmicro.com")
		(comment 9 "footprints 470-474 of 506")
	)
	(layers
		(0 "F.Cu" signal)
		(4 "In1.Cu" power)
		(6 "In2.Cu" power)
		(8 "In3.Cu" signal)
		(10 "In4.Cu" signal)
		(2 "B.Cu" signal)
		(9 "F.Adhes" user "F.Adhesive")
		(11 "B.Adhes" user "B.Adhesive")
		(13 "F.Paste" user)
		(15 "B.Paste" user)
		(5 "F.SilkS" user "F.Silkscreen")
		(7 "B.SilkS" user "B.Silkscreen")
		(1 "F.Mask" user)
		(3 "B.Mask" user)
		(17 "Dwgs.User" user "User.Drawings")
		(19 "Cmts.User" user "User.Comments")
		(21 "Eco1.User" user "User.Eco1")
		(23 "Eco2.User" user "User.Eco2")
		(25 "Edge.Cuts" user)
		(27 "Margin" user)
		(31 "F.CrtYd" user "F.Courtyard")
		(29 "B.CrtYd" user "B.Courtyard")
		(35 "F.Fab" user)
		(33 "B.Fab" user)
	)
	(footprint "antmicro-footprints:R_0402_1005Metric"
		(layer "B.Cu")
		(at 127.3 178.2 -90)
		(descr "Resistor SMD 0402")
		(tags "resistor SMD 0402")
		(property "Reference" "R811"
			(at -3.7 -0.4 270)
			(layer "B.SilkS")
			(effects
				(font
					(size 0.7 0.7)
					(thickness 0.15)
				)
				(justify left bottom mirror)
			)
		)
		(property "Value" "R_2k2_0402"
			(at -1.011843 -1.772047 90)
			(layer "B.Fab")
			(effects
				(font
					(size 0.7 0.7)
					(thickness 0.15)
				)
				(justify left bottom mirror)
			)
		)
		(property "Datasheet" "https://www.bourns.com/docs/product-datasheets/cr.pdf"
			(at 0 0 90)
			(layer "B.Fab")
			(hide yes)
			(effects
				(font
					(size 1.27 1.27)
					(thickness 0.15)
				)
				(justify mirror)
			)
		)
		(property "Description" "SMD Chip Resistor, 2.2 kohm, ± 1%, 62.5 mW, 0402 [1005 Metric], Thick Film, General Purpose"
			(at 0 0 90)
			(layer "B.Fab")
			(hide yes)
			(effects
				(font
					(size 1.27 1.27)
					(thickness 0.15)
				)
				(justify mirror)
			)
		)
		(property "MPN" "CR0402-FX-2201GLF"
			(at 0 0 270)
			(unlocked yes)
			(layer "B.Fab")
			(hide yes)
			(effects
				(font
					(size 1 1)
					(thickness 0.15)
				)
				(justify mirror)
			)
		)
		(property "Manufacturer" "Bourns"
			(at 0 0 270)
			(unlocked yes)
			(layer "B.Fab")
			(hide yes)
			(effects
				(font
					(size 1 1)
					(thickness 0.15)
				)
				(justify mirror)
			)
		)
		(property "License" "Apache-2.0"
			(at 0 0 270)
			(unlocked yes)
			(layer "B.Fab")
			(hide yes)
			(effects
				(font
					(size 1 1)
					(thickness 0.15)
				)
				(justify mirror)
			)
		)
		(property "Author" "Antmicro"
			(at 0 0 270)
			(unlocked yes)
			(layer "B.Fab")
			(hide yes)
			(effects
				(font
					(size 1 1)
					(thickness 0.15)
				)
				(justify mirror)
			)
		)
		(property "Val" "2k2"
			(at 0 0 270)
			(unlocked yes)
			(layer "B.Fab")
			(hide yes)
			(effects
				(font
					(size 1 1)
					(thickness 0.15)
				)
				(justify mirror)
			)
		)
		(property "Tolerance" "1%"
			(at 0 0 270)
			(unlocked yes)
			(layer "B.Fab")
			(hide yes)
			(effects
				(font
					(size 1 1)
					(thickness 0.15)
				)
				(justify mirror)
			)
		)
		(sheetname "/Peripherals/")
		(sheetfile "peripherals.kicad_sch")
		(attr smd)
		(fp_rect
			(start -0.925 0.47)
			(end 0.925 -0.47)
			(stroke
				(width 0.05)
				(type default)
			)
			(fill no)
			(layer "B.CrtYd")
		)
		(fp_rect
			(start -0.5 0.25)
			(end 0.5 -0.25)
			(stroke
				(width 0.15)
				(type solid)
			)
			(fill no)
			(layer "B.Fab")
		)
		(fp_text user "${REFERENCE}"
			(at -0.95 -3.168 90)
			(layer "B.Fab")
			(effects
				(font
					(size 0.7 0.7)
					(thickness 0.15)
				)
				(justify left bottom mirror)
			)
		)
		(fp_text user "Author: Antmicro"
			(at -0.95 -4.169 90)
			(layer "B.Fab")
			(effects
				(font
					(size 0.7 0.7)
					(thickness 0.15)
				)
				(justify left bottom mirror)
			)
		)
		(fp_text user "License: Apache-2.0"
			(at -0.95 -5.169 90)
			(layer "B.Fab")
			(effects
				(font
					(size 0.7 0.7)
					(thickness 0.15)
				)
				(justify left bottom mirror)
			)
		)
		(pad "1" smd roundrect
			(at -0.48 0 270)
			(size 0.59 0.64)
			(layers "B.Cu" "B.Mask" "B.Paste")
			(roundrect_rratio 0.25)
			(net 502 "Net-(BT801-+)")
			(pintype "passive")
		)
		(pad "2" smd roundrect
			(at 0.48 0 270)
			(size 0.59 0.64)
			(layers "B.Cu" "B.Mask" "B.Paste")
			(roundrect_rratio 0.25)
			(net 503 "Net-(D811-C)")
			(pintype "passive")
		)
	)
	(footprint "antmicro-footprints:C_2220_5650Metric"
		(layer "B.Cu")
		(at 43.292962 145.6465 90)
		(descr "Capacitor SMD 2220")
		(tags "capacitor SMD 2220")
		(property "Reference" "C407"
			(at -4.63 -1.275 180)
			(layer "B.SilkS")
			(effects
				(font
					(size 0.7 0.7)
					(thickness 0.15)
				)
				(justify right bottom mirror)
			)
		)
		(property "Value" "C_22u_100V_2220"
			(at 0 -3.9 90)
			(layer "B.Fab")
			(effects
				(font
					(size 0.7 0.7)
					(thickness 0.15)
				)
				(justify right bottom mirror)
			)
		)
		(property "Datasheet" "https://product.tdk.com/en/search/capacitor/ceramic/mlcc/info?part_no=C5750X7S2A226M280KB"
			(at 0 0 90)
			(layer "B.Fab")
			(hide yes)
			(effects
				(font
					(size 1.27 1.27)
					(thickness 0.15)
				)
			)
		)
		(property "Manufacturer" "TDK"
			(at 0 0 90)
			(unlocked yes)
			(layer "B.Fab")
			(hide yes)
			(effects
				(font
					(size 1 1)
					(thickness 0.15)
				)
				(justify mirror)
			)
		)
		(property "MPN" "C5750X7S2A226M280KB"
			(at 0 0 90)
			(unlocked yes)
			(layer "B.Fab")
			(hide yes)
			(effects
				(font
					(size 1 1)
					(thickness 0.15)
				)
				(justify mirror)
			)
		)
		(property "Val" "22u"
			(at 0 0 90)
			(unlocked yes)
			(layer "B.Fab")
			(hide yes)
			(effects
				(font
					(size 1 1)
					(thickness 0.15)
				)
				(justify mirror)
			)
		)
		(property "License" "Apache-2.0"
			(at 0 0 90)
			(unlocked yes)
			(layer "B.Fab")
			(hide yes)
			(effects
				(font
					(size 1 1)
					(thickness 0.15)
				)
				(justify mirror)
			)
		)
		(property "Author" "Antmicro"
			(at 0 0 90)
			(unlocked yes)
			(layer "B.Fab")
			(hide yes)
			(effects
				(font
					(size 1 1)
					(thickness 0.15)
				)
				(justify mirror)
			)
		)
		(property "Voltage" "100V"
			(at 0 0 90)
			(unlocked yes)
			(layer "B.Fab")
			(hide yes)
			(effects
				(font
					(size 1 1)
					(thickness 0.15)
				)
				(justify mirror)
			)
		)
		(property "Dielectric" "X7S"
			(at 0 0 90)
			(unlocked yes)
			(layer "B.Fab")
			(hide yes)
			(effects
				(font
					(size 1 1)
					(thickness 0.15)
				)
				(justify mirror)
			)
		)
		(property "Public" "False"
			(at 0 0 90)
			(unlocked yes)
			(layer "B.Fab")
			(hide yes)
			(effects
				(font
					(size 1 1)
					(thickness 0.15)
				)
				(justify mirror)
			)
		)
		(sheetname "/Ethernet/")
		(sheetfile "ethernet.kicad_sch")
		(attr smd)
		(fp_line
			(start -1.415 -2.61)
			(end 1.415 -2.61)
			(stroke
				(width 0.15)
				(type solid)
			)
			(layer "B.SilkS")
		)
		(fp_line
			(start -1.415 2.61)
			(end 1.415 2.61)
			(stroke
				(width 0.15)
				(type solid)
			)
			(layer "B.SilkS")
		)
		(fp_rect
			(start -3.7 2.95)
			(end 3.7 -2.95)
			(stroke
				(width 0.05)
				(type solid)
			)
			(fill no)
			(layer "B.CrtYd")
		)
		(fp_rect
			(start -2.85 2.5)
			(end 2.85 -2.5)
			(stroke
				(width 0.15)
				(type solid)
			)
			(fill no)
			(layer "B.Fab")
		)
		(fp_text user "License: Apache-2.0"
			(at -3.7 -6.9 270)
			(layer "B.Fab")
			(effects
				(font
					(size 0.7 0.7)
					(thickness 0.15)
				)
				(justify left bottom mirror)
			)
		)
		(fp_text user "${REFERENCE}"
			(at -3.7 -5.9 270)
			(layer "B.Fab")
			(effects
				(font
					(size 0.7 0.7)
					(thickness 0.15)
				)
				(justify left bottom mirror)
			)
		)
		(fp_text user "Author: Antmicro"
			(at -3.7 -7.9 270)
			(layer "B.Fab")
			(effects
				(font
					(size 0.7 0.7)
					(thickness 0.15)
				)
				(justify left bottom mirror)
			)
		)
		(pad "1" smd roundrect
			(at -2.55 0 90)
			(size 1.8 5.4)
			(layers "B.Cu" "B.Mask" "B.Paste")
			(roundrect_rratio 0.138889)
			(net 1 "GNDD")
			(pintype "passive")
		)
		(pad "2" smd roundrect
			(at 2.55 0 90)
			(size 1.8 5.4)
			(layers "B.Cu" "B.Mask" "B.Paste")
			(roundrect_rratio 0.138889)
			(net 33 "/Ethernet/VDD")
			(pintype "passive")
		)
	)
	(footprint "antmicro-footprints:C_0805_2012Metric"
		(layer "B.Cu")
		(at 56.717962 171.3165 -90)
		(descr "Capacitor SMD 0805")
		(tags "capacitor SMD 0805")
		(property "Reference" "C410"
			(at 1.76 -0.4 90)
			(layer "B.SilkS")
			(effects
				(font
					(size 0.7 0.7)
					(thickness 0.15)
				)
				(justify left bottom mirror)
			)
		)
		(property "Value" "C_22u_25V_0805"
			(at -2.055717 -1.963152 90)
			(layer "B.Fab")
			(effects
				(font
					(size 0.7 0.7)
					(thickness 0.15)
				)
				(justify left bottom mirror)
			)
		)
		(property "Datasheet" "https://product.samsungsem.com/mlcc/CL21A226MAYNNN.do"
			(at 0 0 270)
			(layer "B.Fab")
			(hide yes)
			(effects
				(font
					(size 1.27 1.27)
					(thickness 0.15)
				)
			)
		)
		(property "Manufacturer" "Samsung Electro-Mechanics"
			(at 0 0 270)
			(unlocked yes)
			(layer "B.Fab")
			(hide yes)
			(effects
				(font
					(size 1 1)
					(thickness 0.15)
				)
				(justify mirror)
			)
		)
		(property "MPN" "CL21A226MAYNNNE"
			(at 0 0 270)
			(unlocked yes)
			(layer "B.Fab")
			(hide yes)
			(effects
				(font
					(size 1 1)
					(thickness 0.15)
				)
				(justify mirror)
			)
		)
		(property "Val" "22u"
			(at 0 0 270)
			(unlocked yes)
			(layer "B.Fab")
			(hide yes)
			(effects
				(font
					(size 1 1)
					(thickness 0.15)
				)
				(justify mirror)
			)
		)
		(property "License" "Apache-2.0"
			(at 0 0 270)
			(unlocked yes)
			(layer "B.Fab")
			(hide yes)
			(effects
				(font
					(size 1 1)
					(thickness 0.15)
				)
				(justify mirror)
			)
		)
		(property "Author" "Antmicro"
			(at 0 0 270)
			(unlocked yes)
			(layer "B.Fab")
			(hide yes)
			(effects
				(font
					(size 1 1)
					(thickness 0.15)
				)
				(justify mirror)
			)
		)
		(property "Voltage" "25V"
			(at 0 0 270)
			(unlocked yes)
			(layer "B.Fab")
			(hide yes)
			(effects
				(font
					(size 1 1)
					(thickness 0.15)
				)
				(justify mirror)
			)
		)
		(property "Dielectric" "X5R"
			(at 0 0 270)
			(unlocked yes)
			(layer "B.Fab")
			(hide yes)
			(effects
				(font
					(size 1 1)
					(thickness 0.15)
				)
				(justify mirror)
			)
		)
		(property "Public" "False"
			(at 0 0 270)
			(unlocked yes)
			(layer "B.Fab")
			(hide yes)
			(effects
				(font
					(size 1 1)
					(thickness 0.15)
				)
				(justify mirror)
			)
		)
		(sheetname "/Ethernet/")
		(sheetfile "ethernet.kicad_sch")
		(attr smd)
		(fp_line
			(start -0.3 0.7)
			(end 0.3 0.7)
			(stroke
				(width 0.15)
				(type solid)
			)
			(layer "B.SilkS")
		)
		(fp_line
			(start -0.3 -0.7)
			(end 0.3 -0.7)
			(stroke
				(width 0.15)
				(type solid)
			)
			(layer "B.SilkS")
		)
		(fp_rect
			(start 1.95 0.9)
			(end -1.95 -0.9)
			(stroke
				(width 0.05)
				(type default)
			)
			(fill no)
			(layer "B.CrtYd")
		)
		(fp_rect
			(start -0.95 0.675)
			(end 0.95 -0.675)
			(stroke
				(width 0.15)
				(type solid)
			)
			(fill no)
			(layer "B.Fab")
		)
		(fp_text user "License: Apache-2.0"
			(at -1.9 -4.947 90)
			(layer "B.Fab")
			(effects
				(font
					(size 0.7 0.7)
					(thickness 0.15)
				)
				(justify left bottom mirror)
			)
		)
		(fp_text user "${REFERENCE}"
			(at -1.9 -3.947 90)
			(layer "B.Fab")
			(effects
				(font
					(size 0.7 0.7)
					(thickness 0.15)
				)
				(justify left bottom mirror)
			)
		)
		(fp_text user "Author: Antmicro"
			(at -1.9 -5.947 90)
			(layer "B.Fab")
			(effects
				(font
					(size 0.7 0.7)
					(thickness 0.15)
				)
				(justify left bottom mirror)
			)
		)
		(pad "1" smd roundrect
			(at -1.1 0 270)
			(size 1.2 1.3)
			(layers "B.Cu" "B.Mask" "B.Paste")
			(roundrect_rratio 0.25)
			(net 47 "/Ethernet/POE_12V")
			(pintype "passive")
		)
		(pad "2" smd roundrect
			(at 1.1 0 270)
			(size 1.2 1.3)
			(layers "B.Cu" "B.Mask" "B.Paste")
			(roundrect_rratio 0.25)
			(net 3 "GND")
			(pintype "passive")
		)
	)
	(footprint "antmicro-footprints:R_0402_1005Metric"
		(layer "B.Cu")
		(at 119.092962 122.4665 -90)
		(descr "Resistor SMD 0402")
		(tags "resistor SMD 0402")
		(property "Reference" "R501"
			(at 0.72 -0.555 90)
			(layer "B.SilkS")
			(effects
				(font
					(size 0.7 0.7)
					(thickness 0.15)
				)
				(justify left bottom mirror)
			)
		)
		(property "Value" "R_10k_0402"
			(at -1.011843 -1.772047 90)
			(layer "B.Fab")
			(effects
				(font
					(size 0.7 0.7)
					(thickness 0.15)
				)
				(justify left bottom mirror)
			)
		)
		(property "Datasheet" "https://www.bourns.com/docs/product-datasheets/cr.pdf"
			(at 0 0 270)
			(layer "B.Fab")
			(hide yes)
			(effects
				(font
					(size 1.27 1.27)
					(thickness 0.15)
				)
			)
		)
		(property "Manufacturer" "Bourns"
			(at 0 0 270)
			(unlocked yes)
			(layer "B.Fab")
			(hide yes)
			(effects
				(font
					(size 1 1)
					(thickness 0.15)
				)
				(justify mirror)
			)
		)
		(property "MPN" "CR0402-FX-1002GLF"
			(at 0 0 270)
			(unlocked yes)
			(layer "B.Fab")
			(hide yes)
			(effects
				(font
					(size 1 1)
					(thickness 0.15)
				)
				(justify mirror)
			)
		)
		(property "Val" "10k"
			(at 0 0 270)
			(unlocked yes)
			(layer "B.Fab")
			(hide yes)
			(effects
				(font
					(size 1 1)
					(thickness 0.15)
				)
				(justify mirror)
			)
		)
		(property "License" "Apache-2.0"
			(at 0 0 270)
			(unlocked yes)
			(layer "B.Fab")
			(hide yes)
			(effects
				(font
					(size 1 1)
					(thickness 0.15)
				)
				(justify mirror)
			)
		)
		(property "Author" "Antmicro"
			(at 0 0 270)
			(unlocked yes)
			(layer "B.Fab")
			(hide yes)
			(effects
				(font
					(size 1 1)
					(thickness 0.15)
				)
				(justify mirror)
			)
		)
		(property "Tolerance" "1%"
			(at 0 0 270)
			(unlocked yes)
			(layer "B.Fab")
			(hide yes)
			(effects
				(font
					(size 1 1)
					(thickness 0.15)
				)
				(justify mirror)
			)
		)
		(sheetname "/NVMe & microSD/")
		(sheetfile "nvme-micro-sd.kicad_sch")
		(attr smd)
		(fp_rect
			(start -0.925 0.47)
			(end 0.925 -0.47)
			(stroke
				(width 0.05)
				(type default)
			)
			(fill no)
			(layer "B.CrtYd")
		)
		(fp_rect
			(start -0.5 0.25)
			(end 0.5 -0.25)
			(stroke
				(width 0.15)
				(type solid)
			)
			(fill no)
			(layer "B.Fab")
		)
		(fp_text user "Author: Antmicro"
			(at -0.95 -4.169 90)
			(layer "B.Fab")
			(effects
				(font
					(size 0.7 0.7)
					(thickness 0.15)
				)
				(justify left bottom mirror)
			)
		)
		(fp_text user "License: Apache-2.0"
			(at -0.95 -5.169 90)
			(layer "B.Fab")
			(effects
				(font
					(size 0.7 0.7)
					(thickness 0.15)
				)
				(justify left bottom mirror)
			)
		)
		(fp_text user "${REFERENCE}"
			(at -0.95 -3.168 90)
			(layer "B.Fab")
			(effects
				(font
					(size 0.7 0.7)
					(thickness 0.15)
				)
				(justify left bottom mirror)
			)
		)
		(pad "1" smd roundrect
			(at -0.48 0 270)
			(size 0.59 0.64)
			(layers "B.Cu" "B.Mask" "B.Paste")
			(roundrect_rratio 0.25)
			(net 145 "/Compute module/NVMe.~{RST}")
			(pintype "passive")
		)
		(pad "2" smd roundrect
			(at 0.48 0 270)
			(size 0.59 0.64)
			(layers "B.Cu" "B.Mask" "B.Paste")
			(roundrect_rratio 0.25)
			(net 65 "3V3_SSD")
			(pintype "passive")
		)
	)
	(footprint "antmicro-footprints:R_0402_1005Metric"
		(layer "B.Cu")
		(at 92.537962 153.3915)
		(descr "Resistor SMD 0402")
		(tags "resistor SMD 0402")
		(property "Reference" "R232"
			(at -0.99 3.96 0)
			(layer "B.SilkS")
			(effects
				(font
					(size 0.7 0.7)
					(thickness 0.15)
				)
				(justify right bottom mirror)
			)
		)
		(property "Value" "R_10k_0402"
			(at -1.011843 -1.772047 0)
			(layer "B.Fab")
			(effects
				(font
					(size 0.7 0.7)
					(thickness 0.15)
				)
				(justify right bottom mirror)
			)
		)
		(property "Datasheet" "https://www.bourns.com/docs/product-datasheets/cr.pdf"
			(at 0 0 0)
			(layer "B.Fab")
			(hide yes)
			(effects
				(font
					(size 1.27 1.27)
					(thickness 0.15)
				)
			)
		)
		(property "MPN" "CR0402-FX-1002GLF"
			(at 0 0 0)
			(unlocked yes)
			(layer "B.Fab")
			(hide yes)
			(effects
				(font
					(size 1 1)
					(thickness 0.15)
				)
				(justify mirror)
			)
		)
		(property "Manufacturer" "Bourns"
			(at 0 0 0)
			(unlocked yes)
			(layer "B.Fab")
			(hide yes)
			(effects
				(font
					(size 1 1)
					(thickness 0.15)
				)
				(justify mirror)
			)
		)
		(property "License" "Apache-2.0"
			(at 0 0 0)
			(unlocked yes)
			(layer "B.Fab")
			(hide yes)
			(effects
				(font
					(size 1 1)
					(thickness 0.15)
				)
				(justify mirror)
			)
		)
		(property "Author" "Antmicro"
			(at 0 0 0)
			(unlocked yes)
			(layer "B.Fab")
			(hide yes)
			(effects
				(font
					(size 1 1)
					(thickness 0.15)
				)
				(justify mirror)
			)
		)
		(property "Val" "10k"
			(at 0 0 0)
			(unlocked yes)
			(layer "B.Fab")
			(hide yes)
			(effects
				(font
					(size 1 1)
					(thickness 0.15)
				)
				(justify mirror)
			)
		)
		(property "Tolerance" "1%"
			(at 0 0 0)
			(unlocked yes)
			(layer "B.Fab")
			(hide yes)
			(effects
				(font
					(size 1 1)
					(thickness 0.15)
				)
				(justify mirror)
			)
		)
		(sheetname "/Compute module/")
		(sheetfile "compute-module.kicad_sch")
		(attr smd exclude_from_pos_files exclude_from_bom dnp)
		(fp_rect
			(start -0.925 0.47)
			(end 0.925 -0.47)
			(stroke
				(width 0.05)
				(type default)
			)
			(fill no)
			(layer "B.CrtYd")
		)
		(fp_rect
			(start -0.5 0.25)
			(end 0.5 -0.25)
			(stroke
				(width 0.15)
				(type solid)
			)
			(fill no)
			(layer "B.Fab")
		)
		(fp_text user "License: Apache-2.0"
			(at -0.95 -5.169 180)
			(layer "B.Fab")
			(effects
				(font
					(size 0.7 0.7)
					(thickness 0.15)
				)
				(justify left bottom mirror)
			)
		)
		(fp_text user "${REFERENCE}"
			(at -0.95 -3.168 180)
			(layer "B.Fab")
			(effects
				(font
					(size 0.7 0.7)
					(thickness 0.15)
				)
				(justify left bottom mirror)
			)
		)
		(fp_text user "Author: Antmicro"
			(at -0.95 -4.169 180)
			(layer "B.Fab")
			(effects
				(font
					(size 0.7 0.7)
					(thickness 0.15)
				)
				(justify left bottom mirror)
			)
		)
		(pad "1" smd roundrect
			(at -0.48 0)
			(size 0.59 0.64)
			(layers "B.Cu" "B.Mask" "B.Paste")
			(roundrect_rratio 0.25)
			(net 346 "Net-(U204-A1)")
			(pintype "passive")
		)
		(pad "2" smd roundrect
			(at 0.48 0)
			(size 0.59 0.64)
			(layers "B.Cu" "B.Mask" "B.Paste")
			(roundrect_rratio 0.25)
			(net 9 "+3V3")
			(pintype "passive")
		)
	)
)
